FILE_TYPE=LIBRARY_PARTS;
primitive 'SN74LVC1G07DCKR';
  pin
    'VCC':
      PIN_NUMBER='(5)';
      PINUSE='POWER';
      NO_LOAD_CHECK='Both';
      NO_IO_CHECK='Both';
      NO_ASSERT_CHECK='TRUE';
      NO_DIR_CHECK='TRUE';
      ALLOW_CONNECT='TRUE';
    'A':
      PIN_NUMBER='(2)';
      INPUT_LOAD='(-0.01,0.01)';
    'GND':
      PIN_NUMBER='(3)';
      PINUSE='POWER';
      NO_LOAD_CHECK='Both';
      NO_IO_CHECK='Both';
      NO_ASSERT_CHECK='TRUE';
      NO_DIR_CHECK='TRUE';
      ALLOW_CONNECT='TRUE';
    'Y':
      PIN_NUMBER='(4)';
      OUTPUT_TYPE='(OC,AND)';
      OUTPUT_LOAD='(1.0,*)';
    'NC1':
      PIN_NUMBER='(1)';
      OUTPUT_TYPE='(TS,TS)';
      INPUT_LOAD='(-0.01,0.01)';
      OUTPUT_LOAD='(1.0,-1.0)';
  end_pin;
  body
    PART_NAME='SN74LVC1G07DCKR';
    BODY_NAME='SN74LVC1G07DCKR';
    PHYS_DES_PREFIX='U';
    CLASS='IC';
  end_body;
end_primitive;

END.
